# S9S_MB_2U (Grand Teton) — schematic netlist excerpt (pin names and nets, part order shuffled) for the footprints in the layout excerpt that follows; sources: Cadence DE-HDL packaged netlist, KiCad conversion of 03242023_DA0F0TMBIJ0_F0T_Motherboard_J_brd_V01_OCP.brd

PR202  Q_RES  28K 1% EMPTY  pkg 0402LF  page 296 : A = PVCCD_HV_CPU1_VREF ; B = PVCCD_HV_CPU1_ADDR
R4639  Q_RES  243 1% CHIP  pkg 1206LF  page 260 : A = P5V ; B = VR_P5V_EN_D
R4657  Q_RES  1K 1% EMPTY  pkg 0402LF  page 167 : A = FM_P2E_BUF2_SD_TH ; B = GND

(kicad_pcb
	(version 20260206)
	(generator "pcbnew")
	(generator_version "10.0")
	(general
		(thickness 1.6)
		(legacy_teardrops no)
	)
	(paper "A4")
	(title_block
		(title "03242023_DA0F0TMBIJ0_F0T_Motherboard_J_brd_V01_OCP.brd")
		(comment 1 "Grand Teton / footprints 3662-3664 of 6105")
	)
	(layers
		(0 "F.Cu" signal "TOP")
		(4 "In1.Cu" signal "GND")
		(6 "In2.Cu" signal "IN1")
		(8 "In3.Cu" signal "GND1")
		(10 "In4.Cu" signal "IN2")
		(12 "In5.Cu" signal "GND2")
		(14 "In6.Cu" signal "IN3")
		(16 "In7.Cu" signal "GND3")
		(18 "In8.Cu" signal "VCC")
		(20 "In9.Cu" signal "VCC1")
		(22 "In10.Cu" signal "GND4")
		(24 "In11.Cu" signal "IN4")
		(26 "In12.Cu" signal "GND5")
		(28 "In13.Cu" signal "IN5")
		(30 "In14.Cu" signal "GND6")
		(32 "In15.Cu" signal "IN6")
		(34 "In16.Cu" signal "GND7")
		(2 "B.Cu" signal "BOTTOM")
		(9 "F.Adhes" user "F.Adhesive")
		(11 "B.Adhes" user "B.Adhesive")
		(13 "F.Paste" user "Package Geometry/Pastemask Top")
		(15 "B.Paste" user "Package Geometry/Pastemask Bottom")
		(5 "F.SilkS" user "Ref Des/Silkscreen Top")
		(7 "B.SilkS" user "Ref Des/Silkscreen Bottom")
		(1 "F.Mask" user "Board Geometry/Soldermask Top")
		(3 "B.Mask" user "Board Geometry/Soldermask Bottom")
		(17 "Dwgs.User" user "User.Drawings")
		(19 "Cmts.User" user "User.Comments")
		(21 "Eco1.User" user "User.Eco1")
		(23 "Eco2.User" user "User.Eco2")
		(25 "Edge.Cuts" user "Board Geometry/Outline")
		(27 "Margin" user)
		(31 "F.CrtYd" user "Package Geometry/Place Bound Top")
		(29 "B.CrtYd" user "Package Geometry/Place Bound Bottom")
		(35 "F.Fab" user "Ref Des/Assembly Top")
		(33 "B.Fab" user "Ref Des/Assembly Bottom")
	)
	(footprint ""
		(layer "F.Cu")
		(at 31.937452 -162.586162 180)
		(property "Reference" "PR202"
			(at 0 0 180)
			(layer "F.SilkS")
			(hide yes)
			(effects
				(font
					(size 1.27 1.27)
				)
			)
		)
		(property "Value" ""
			(at 0 0 180)
			(layer "F.Fab")
			(effects
				(font
					(size 1.27 1.27)
				)
			)
		)
		(duplicate_pad_numbers_are_jumpers no)
		(fp_line
			(start 0.7874 0.4064)
			(end -0.7874 0.4064)
			(stroke
				(width 0.1524)
				(type default)
			)
			(layer "F.SilkS")
		)
		(fp_line
			(start 0.7874 -0.4064)
			(end 0.7874 0.4064)
			(stroke
				(width 0.1524)
				(type default)
			)
			(layer "F.SilkS")
		)
		(fp_line
			(start -0.7874 0.4064)
			(end -0.7874 -0.4064)
			(stroke
				(width 0.1524)
				(type default)
			)
			(layer "F.SilkS")
		)
		(fp_line
			(start -0.7874 -0.4064)
			(end 0.7874 -0.4064)
			(stroke
				(width 0.1524)
				(type default)
			)
			(layer "F.SilkS")
		)
		(fp_line
			(start 0.67945 0.3048)
			(end 0.120396 0.3048)
			(stroke
				(width 0.1)
				(type default)
			)
			(layer "F.Fab")
		)
		(fp_line
			(start 0.67945 -0.3048)
			(end 0.67945 0.3048)
			(stroke
				(width 0.1)
				(type default)
			)
			(layer "F.Fab")
		)
		(fp_line
			(start 0.12065 -0.2794)
			(end 0.12065 -0.3048)
			(stroke
				(width 0.1)
				(type default)
			)
			(layer "F.Fab")
		)
		(fp_line
			(start 0.12065 -0.3048)
			(end 0.67945 -0.3048)
			(stroke
				(width 0.1)
				(type default)
			)
			(layer "F.Fab")
		)
		(fp_line
			(start 0.120396 0.3048)
			(end 0.120396 0.2794)
			(stroke
				(width 0.1)
				(type default)
			)
			(layer "F.Fab")
		)
		(fp_line
			(start 0.120396 0.2794)
			(end -0.12065 0.2794)
			(stroke
				(width 0.1)
				(type default)
			)
			(layer "F.Fab")
		)
		(fp_line
			(start -0.12065 0.3048)
			(end -0.67945 0.3048)
			(stroke
				(width 0.1)
				(type default)
			)
			(layer "F.Fab")
		)
		(fp_line
			(start -0.12065 0.2794)
			(end -0.12065 0.3048)
			(stroke
				(width 0.1)
				(type default)
			)
			(layer "F.Fab")
		)
		(fp_line
			(start -0.12065 -0.2794)
			(end 0.12065 -0.2794)
			(stroke
				(width 0.1)
				(type default)
			)
			(layer "F.Fab")
		)
		(fp_line
			(start -0.12065 -0.305054)
			(end -0.12065 -0.2794)
			(stroke
				(width 0.1)
				(type default)
			)
			(layer "F.Fab")
		)
		(fp_line
			(start -0.67945 0.3048)
			(end -0.67945 -0.305054)
			(stroke
				(width 0.1)
				(type default)
			)
			(layer "F.Fab")
		)
		(fp_line
			(start -0.67945 -0.305054)
			(end -0.12065 -0.305054)
			(stroke
				(width 0.1)
				(type default)
			)
			(layer "F.Fab")
		)
		(pad "1" smd circle
			(at -0.40005 0 180)
			(size 0 0)
			(layers "F.Cu" "F.Mask" "F.Paste")
			(net "PVCCD_HV_CPU1_VREF")
		)
		(pad "2" smd circle
			(at 0.40005 0 180)
			(size 0 0)
			(layers "F.Cu" "F.Mask" "F.Paste")
			(net "PVCCD_HV_CPU1_ADDR")
		)
	)
	(footprint ""
		(layer "F.Cu")
		(at 33.472374 -393.17549 180)
		(property "Reference" "R4657"
			(at 0 0 180)
			(layer "F.SilkS")
			(hide yes)
			(effects
				(font
					(size 1.27 1.27)
				)
			)
		)
		(property "Value" ""
			(at 0 0 180)
			(layer "F.Fab")
			(effects
				(font
					(size 1.27 1.27)
				)
			)
		)
		(duplicate_pad_numbers_are_jumpers no)
		(fp_line
			(start 0.7874 0.4064)
			(end -0.7874 0.4064)
			(stroke
				(width 0.1524)
				(type default)
			)
			(layer "F.SilkS")
		)
		(fp_line
			(start 0.7874 -0.4064)
			(end 0.7874 0.4064)
			(stroke
				(width 0.1524)
				(type default)
			)
			(layer "F.SilkS")
		)
		(fp_line
			(start -0.7874 0.4064)
			(end -0.7874 -0.4064)
			(stroke
				(width 0.1524)
				(type default)
			)
			(layer "F.SilkS")
		)
		(fp_line
			(start -0.7874 -0.4064)
			(end 0.7874 -0.4064)
			(stroke
				(width 0.1524)
				(type default)
			)
			(layer "F.SilkS")
		)
		(fp_line
			(start 0.67945 0.3048)
			(end 0.120396 0.3048)
			(stroke
				(width 0.1)
				(type default)
			)
			(layer "F.Fab")
		)
		(fp_line
			(start 0.67945 -0.3048)
			(end 0.67945 0.3048)
			(stroke
				(width 0.1)
				(type default)
			)
			(layer "F.Fab")
		)
		(fp_line
			(start 0.12065 -0.2794)
			(end 0.12065 -0.3048)
			(stroke
				(width 0.1)
				(type default)
			)
			(layer "F.Fab")
		)
		(fp_line
			(start 0.12065 -0.3048)
			(end 0.67945 -0.3048)
			(stroke
				(width 0.1)
				(type default)
			)
			(layer "F.Fab")
		)
		(fp_line
			(start 0.120396 0.3048)
			(end 0.120396 0.2794)
			(stroke
				(width 0.1)
				(type default)
			)
			(layer "F.Fab")
		)
		(fp_line
			(start 0.120396 0.2794)
			(end -0.12065 0.2794)
			(stroke
				(width 0.1)
				(type default)
			)
			(layer "F.Fab")
		)
		(fp_line
			(start -0.12065 0.3048)
			(end -0.67945 0.3048)
			(stroke
				(width 0.1)
				(type default)
			)
			(layer "F.Fab")
		)
		(fp_line
			(start -0.12065 0.2794)
			(end -0.12065 0.3048)
			(stroke
				(width 0.1)
				(type default)
			)
			(layer "F.Fab")
		)
		(fp_line
			(start -0.12065 -0.2794)
			(end 0.12065 -0.2794)
			(stroke
				(width 0.1)
				(type default)
			)
			(layer "F.Fab")
		)
		(fp_line
			(start -0.12065 -0.305054)
			(end -0.12065 -0.2794)
			(stroke
				(width 0.1)
				(type default)
			)
			(layer "F.Fab")
		)
		(fp_line
			(start -0.67945 0.3048)
			(end -0.67945 -0.305054)
			(stroke
				(width 0.1)
				(type default)
			)
			(layer "F.Fab")
		)
		(fp_line
			(start -0.67945 -0.305054)
			(end -0.12065 -0.305054)
			(stroke
				(width 0.1)
				(type default)
			)
			(layer "F.Fab")
		)
		(pad "1" smd circle
			(at -0.40005 0 180)
			(size 0 0)
			(layers "F.Cu" "F.Mask" "F.Paste")
			(net "FM_P2E_BUF2_SD_TH")
		)
		(pad "2" smd circle
			(at 0.40005 0 180)
			(size 0 0)
			(layers "F.Cu" "F.Mask" "F.Paste")
			(net "GND")
		)
	)
	(footprint ""
		(layer "F.Cu")
		(at 157.226 -126.365 -90)
		(property "Reference" "R4639"
			(at 0 0 270)
			(layer "F.SilkS")
			(hide yes)
			(effects
				(font
					(size 1.27 1.27)
				)
			)
		)
		(property "Value" ""
			(at 0 0 270)
			(layer "F.Fab")
			(effects
				(font
					(size 1.27 1.27)
				)
			)
		)
		(duplicate_pad_numbers_are_jumpers no)
		(fp_line
			(start -2.234946 0.9271)
			(end -2.234946 -0.9271)
			(stroke
				(width 0.1524)
				(type default)
			)
			(layer "F.SilkS")
		)
		(fp_line
			(start 2.234946 0.9271)
			(end -2.234946 0.9271)
			(stroke
				(width 0.1524)
				(type default)
			)
			(layer "F.SilkS")
		)
		(fp_line
			(start -2.234946 -0.9271)
			(end 2.234946 -0.9271)
			(stroke
				(width 0.1524)
				(type default)
			)
			(layer "F.SilkS")
		)
		(fp_line
			(start 2.234946 -0.9271)
			(end 2.234946 0.9271)
			(stroke
				(width 0.1524)
				(type default)
			)
			(layer "F.SilkS")
		)
		(fp_line
			(start -1.575054 0.824992)
			(end 1.575054 0.824992)
			(stroke
				(width 0.1)
				(type default)
			)
			(layer "F.Fab")
		)
		(fp_line
			(start 1.575054 0.824992)
			(end 1.575054 -0.824992)
			(stroke
				(width 0.1)
				(type default)
			)
			(layer "F.Fab")
		)
		(fp_line
			(start -1.575054 -0.824992)
			(end -1.575054 0.824992)
			(stroke
				(width 0.1)
				(type default)
			)
			(layer "F.Fab")
		)
		(fp_line
			(start 1.575054 -0.824992)
			(end -1.575054 -0.824992)
			(stroke
				(width 0.1)
				(type default)
			)
			(layer "F.Fab")
		)
		(pad "1" smd rect
			(at -1.599946 0 270)
			(size 1.016 1.6002)
			(layers "F.Cu" "F.Mask" "F.Paste")
			(net "P5V")
		)
		(pad "2" smd rect
			(at 1.599946 0 270)
			(size 1.016 1.6002)
			(layers "F.Cu" "F.Mask" "F.Paste")
			(net "VR_P5V_EN_D")
		)
	)
)
